FILE_TYPE = CONNECTIVITY;
{Allegro Design Entry HDL 17.4-2019 S026 (4007227) 1/17/2022}
"PAGE_NUMBER" = 402;
0"NC";
1"P5E_CPU1_P0_RX_BUF_DP<7:0>";
2"P5E_CPU1_P0_RX_BUF_DN<7:0>";
3"P5E_CPU1_P0_RX_BUF_DP<15:8>";
4"P5E_CPU1_P0_RX_BUF_DN<15:8>";
5"P5E_CPU1_P0_RX_BUF_DP<11>";
6"P5E_CPU1_P0_RX_BUF_DP<10>";
7"P5E_CPU1_P0_RX_BUF_DP<9>";
8"P5E_CPU1_P0_RX_BUF_DN<8>";
9"P5E_CPU1_P0_RX_BUF_DN<11>";
10"P5E_CPU1_P0_RX_BUF_DN<10>";
11"P5E_CPU1_P0_RX_BUF_DP<14>";
12"P5E_CPU1_P0_RX_BUF_DP<1>";
13"P5E_CPU1_P0_RX_BUF_DP<3>";
14"P5E_CPU1_P0_RX_BUF_DP<4>";
15"P5E_CPU1_P0_RX_BUF_DP<6>";
16"P5E_CPU1_P0_RX_BUF_DN<4>";
17"P5E_CPU1_P0_RX_BUF_DN<2>";
18"P5E_CPU1_P0_RX_BUF_DP<2>";
19"P5E_CPU1_P0_RX_BUF_DN<13>";
20"P5E_CPU1_P0_RX_BUF_DP<13>";
21"P5E_CPU1_P0_RX_BUF_DP<12>";
22"P5E_CPU1_P0_RX_BUF_DP<8>";
23"P5E_CPU1_P0_RX_BUF_DN<9>";
24"P5E_CPU1_P0_RX_BUF_DN<12>";
25"P5E_CPU1_P0_RX_BUF_DN<14>";
26"P5E_CPU1_P0_RX_BUF_DN<15>";
27"P5E_CPU1_P0_RX_BUF_DP<15>";
28"P5E_CPU1_P0_RX_BUF_DN<7>";
29"P5E_CPU1_P0_RX_BUF_DP<0>";
30"P5E_CPU1_P0_RX_BUF_DN<1>";
31"P5E_CPU1_P0_RX_BUF_DN<3>";
32"P5E_CPU1_P0_RX_BUF_DN<0>";
33"P5E_CPU1_P0_RX_BUF_DN<5>";
34"P5E_CPU1_P0_RX_BUF_DP<5>";
35"P5E_CPU1_P0_RX_BUF_DN<6>";
36"P5E_CPU1_P0_RX_BUF_DP<7>";
%"PT5161LRS"
"1","(-7675,3775)","0","pure_quanta","I1";
;
LOCATION"U6014"
$SEC"1"
CDS_SEC"1"
VALUE"PT5161LRS"
MATERIAL"IC"
PART_TYPE"SMLF"
NEEDS_NO_SIZE"TRUE"
CDS_LMAN_SYM_OUTLINE"-350,1450,300,-1400"
CDS_LIB"pure_quanta"
PART_NUMBER"AJ051610U03";
"A_PERN7"
$PN"CB2"8;
"A_PERP7"
$PN"CD1"22;
"A_PERN6"
$PN"BR2"23;
"A_PERP6"
$PN"BU1"7;
"A_PERN5"
$PN"BH2"10;
"A_PERP5"
$PN"BK1"6;
"A_PERN4"
$PN"BA2"9;
"A_PERP4"
$PN"BC1"5;
"A_PERN3"
$PN"AP2"24;
"A_PERP3"
$PN"AT1"21;
"A_PERN2"
$PN"AG2"19;
"A_PERP2"
$PN"AJ1"20;
"A_PERN1"
$PN"Y2"25;
"A_PERP1"
$PN"AB1"11;
"A_PERN0"
$PN"N2"26;
"A_PERP0"
$PN"R1"27;
%"TAP"
"1","(-6450,3875)","0","standard","I10";
;
CDS_LIB"standard"
BODY_TYPE"PLUMBING"
HDL_TAP"TRUE";
"B \NAC \NWC"4;
"S \NAC"
BN"12"24;
%"TAP"
"1","(-6650,3975)","0","standard","I11";
;
CDS_LIB"standard"
BODY_TYPE"PLUMBING"
HDL_TAP"TRUE";
"B \NAC \NWC"3;
"S \NAC"
BN"12"21;
%"TAP"
"1","(-6450,4225)","0","standard","I12";
;
CDS_LIB"standard"
BODY_TYPE"PLUMBING"
HDL_TAP"TRUE";
"B \NAC \NWC"4;
"S \NAC"
BN"13"19;
%"TAP"
"1","(-6650,4325)","0","standard","I13";
;
CDS_LIB"standard"
BODY_TYPE"PLUMBING"
HDL_TAP"TRUE";
"B \NAC \NWC"3;
"S \NAC"
BN"13"20;
%"TAP"
"1","(-6450,4575)","0","standard","I14";
;
CDS_LIB"standard"
BODY_TYPE"PLUMBING"
HDL_TAP"TRUE";
"B \NAC \NWC"4;
"S \NAC"
BN"14"25;
%"TAP"
"1","(-6650,4675)","0","standard","I15";
;
CDS_LIB"standard"
BODY_TYPE"PLUMBING"
HDL_TAP"TRUE";
"B \NAC \NWC"3;
"S \NAC"
BN"14"11;
%"TAP"
"1","(-6650,5025)","0","standard","I16";
;
CDS_LIB"standard"
BODY_TYPE"PLUMBING"
HDL_TAP"TRUE";
"B \NAC \NWC"3;
"S \NAC"
BN"15"27;
%"TAP"
"1","(-6450,4925)","0","standard","I17";
;
CDS_LIB"standard"
BODY_TYPE"PLUMBING"
HDL_TAP"TRUE";
"B \NAC \NWC"4;
"S \NAC"
BN"15"26;
%"TAP"
"1","(-6650,2575)","0","standard","I2";
;
CDS_LIB"standard"
BODY_TYPE"PLUMBING"
HDL_TAP"TRUE";
"B \NAC \NWC"3;
"S \NAC"
BN"8"22;
%"TAP"
"1","(-2200,2600)","0","standard","I20";
;
CDS_LIB"standard"
BODY_TYPE"PLUMBING"
HDL_TAP"TRUE";
"B \NAC \NWC"1;
"S \NAC"
BN"0"29;
%"TAP"
"1","(-2000,2500)","0","standard","I21";
;
CDS_LIB"standard"
BODY_TYPE"PLUMBING"
HDL_TAP"TRUE";
"B \NAC \NWC"2;
"S \NAC"
BN"0"32;
%"TAP"
"1","(-2200,2950)","0","standard","I22";
;
CDS_LIB"standard"
BODY_TYPE"PLUMBING"
HDL_TAP"TRUE";
"B \NAC \NWC"1;
"S \NAC"
BN"1"12;
%"TAP"
"1","(-2200,3300)","0","standard","I23";
;
CDS_LIB"standard"
BODY_TYPE"PLUMBING"
HDL_TAP"TRUE";
"B \NAC \NWC"1;
"S \NAC"
BN"2"18;
%"TAP"
"1","(-2200,3650)","0","standard","I24";
;
CDS_LIB"standard"
BODY_TYPE"PLUMBING"
HDL_TAP"TRUE";
"B \NAC \NWC"1;
"S \NAC"
BN"3"13;
%"TAP"
"1","(-2000,3200)","0","standard","I25";
;
CDS_LIB"standard"
BODY_TYPE"PLUMBING"
HDL_TAP"TRUE";
"B \NAC \NWC"2;
"S \NAC"
BN"2"17;
%"TAP"
"1","(-2000,3550)","0","standard","I26";
;
CDS_LIB"standard"
BODY_TYPE"PLUMBING"
HDL_TAP"TRUE";
"B \NAC \NWC"2;
"S \NAC"
BN"3"31;
%"TAP"
"1","(-2200,4000)","0","standard","I27";
;
CDS_LIB"standard"
BODY_TYPE"PLUMBING"
HDL_TAP"TRUE";
"B \NAC \NWC"1;
"S \NAC"
BN"4"14;
%"TAP"
"1","(-2200,4350)","0","standard","I28";
;
CDS_LIB"standard"
BODY_TYPE"PLUMBING"
HDL_TAP"TRUE";
"B \NAC \NWC"1;
"S \NAC"
BN"5"34;
%"TAP"
"1","(-2200,4700)","0","standard","I29";
;
CDS_LIB"standard"
BODY_TYPE"PLUMBING"
HDL_TAP"TRUE";
"B \NAC \NWC"1;
"S \NAC"
BN"6"15;
%"TAP"
"1","(-6450,2475)","0","standard","I3";
;
CDS_LIB"standard"
BODY_TYPE"PLUMBING"
HDL_TAP"TRUE";
"B \NAC \NWC"4;
"S \NAC"
BN"8"8;
%"TAP"
"1","(-2000,3900)","0","standard","I30";
;
CDS_LIB"standard"
BODY_TYPE"PLUMBING"
HDL_TAP"TRUE";
"B \NAC \NWC"2;
"S \NAC"
BN"4"16;
%"TAP"
"1","(-2000,4250)","0","standard","I31";
;
CDS_LIB"standard"
BODY_TYPE"PLUMBING"
HDL_TAP"TRUE";
"B \NAC \NWC"2;
"S \NAC"
BN"5"33;
%"TAP"
"1","(-2000,4600)","0","standard","I32";
;
CDS_LIB"standard"
BODY_TYPE"PLUMBING"
HDL_TAP"TRUE";
"B \NAC \NWC"2;
"S \NAC"
BN"6"35;
%"TAP"
"1","(-2200,5050)","0","standard","I33";
;
CDS_LIB"standard"
BODY_TYPE"PLUMBING"
HDL_TAP"TRUE";
"B \NAC \NWC"1;
"S \NAC"
BN"7"36;
%"TAP"
"1","(-2000,4950)","0","standard","I34";
;
CDS_LIB"standard"
BODY_TYPE"PLUMBING"
HDL_TAP"TRUE";
"B \NAC \NWC"2;
"S \NAC"
BN"7"28;
%"TAP"
"1","(-2000,2850)","0","standard","I37";
;
CDS_LIB"standard"
BODY_TYPE"PLUMBING"
HDL_TAP"TRUE";
"B \NAC \NWC"2;
"S \NAC"
BN"1"30;
%"PT5161LRS"
"2","(-3225,3800)","0","pure_quanta","I38";
;
LOCATION"U6014"
$SEC"2"
CDS_SEC"2"
PART_TYPE"SMLF"
MATERIAL"IC"
VALUE"PT5161LRS"
CDS_LIB"pure_quanta"
CDS_LMAN_SYM_OUTLINE"-350,1450,300,-1400"
NEEDS_NO_SIZE"TRUE"
PART_NUMBER"AJ051610U03";
"A_PERN15"
$PN"EV2"32;
"A_PERP15"
$PN"EY1"29;
"A_PERN14"
$PN"EL2"30;
"A_PERP14"
$PN"EN1"12;
"A_PERN13"
$PN"ED2"17;
"A_PERP13"
$PN"EF1"18;
"A_PERN12"
$PN"DU2"31;
"A_PERP12"
$PN"DW1"13;
"A_PERN11"
$PN"DK2"16;
"A_PERP11"
$PN"DM1"14;
"A_PERN10"
$PN"DC2"33;
"A_PERP10"
$PN"DE1"34;
"A_PERN9"
$PN"CT2"35;
"A_PERP9"
$PN"CV1"15;
"A_PERN8"
$PN"CJ2"28;
"A_PERP8"
$PN"CL1"36;
%"TAP"
"1","(-6650,2925)","0","standard","I4";
;
CDS_LIB"standard"
BODY_TYPE"PLUMBING"
HDL_TAP"TRUE";
"B \NAC \NWC"3;
"S \NAC"
BN"9"7;
%"TAP"
"1","(-6450,2825)","0","standard","I5";
;
CDS_LIB"standard"
BODY_TYPE"PLUMBING"
HDL_TAP"TRUE";
"B \NAC \NWC"4;
"S \NAC"
BN"9"23;
%"TAP"
"1","(-6650,3275)","0","standard","I6";
;
CDS_LIB"standard"
BODY_TYPE"PLUMBING"
HDL_TAP"TRUE";
"B \NAC \NWC"3;
"S \NAC"
BN"10"6;
%"TAP"
"1","(-6450,3175)","0","standard","I7";
;
CDS_LIB"standard"
BODY_TYPE"PLUMBING"
HDL_TAP"TRUE";
"B \NAC \NWC"4;
"S \NAC"
BN"10"10;
%"TAP"
"1","(-6450,3525)","0","standard","I8";
;
CDS_LIB"standard"
BODY_TYPE"PLUMBING"
HDL_TAP"TRUE";
"B \NAC \NWC"4;
"S \NAC"
BN"11"9;
%"TAP"
"1","(-6650,3625)","0","standard","I9";
;
CDS_LIB"standard"
BODY_TYPE"PLUMBING"
HDL_TAP"TRUE";
"B \NAC \NWC"3;
"S \NAC"
BN"11"5;
END.
